(kicad_pcb
	(version 20260206)
	(generator "pcbnew")
	(generator_version "10.0")
	(general
		(thickness 1.6)
		(legacy_teardrops no)
	)
	(paper "A4")
	(title_block
		(title "panther-plus-userver — 13130-1b_20150205.brd")
		(comment 1 "Honey Badger (Wiwynn) / footprints 167-173 of 1509")
	)
	(layers
		(0 "F.Cu" signal "TOP")
		(4 "In1.Cu" signal "L2")
		(6 "In2.Cu" signal "L3")
		(8 "In3.Cu" signal "L4")
		(10 "In4.Cu" signal "L5")
		(12 "In5.Cu" signal "L6")
		(14 "In6.Cu" signal "L7")
		(16 "In7.Cu" signal "L8")
		(18 "In8.Cu" signal "L9")
		(20 "In9.Cu" signal "L10")
		(22 "In10.Cu" signal "L11")
		(2 "B.Cu" signal "BOTTOM")
		(9 "F.Adhes" user "F.Adhesive")
		(11 "B.Adhes" user "B.Adhesive")
		(13 "F.Paste" user "Package Geometry/Pastemask Top")
		(15 "B.Paste" user "Package Geometry/Pastemask Bottom")
		(5 "F.SilkS" user "Ref Des/Silkscreen Top")
		(7 "B.SilkS" user "Ref Des/Silkscreen Bottom")
		(1 "F.Mask" user "Board Geometry/Soldermask Top")
		(3 "B.Mask" user "Board Geometry/Soldermask Bottom")
		(17 "Dwgs.User" user "User.Drawings")
		(19 "Cmts.User" user "User.Comments")
		(21 "Eco1.User" user "User.Eco1")
		(23 "Eco2.User" user "User.Eco2")
		(25 "Edge.Cuts" user "Board Geometry/Outline")
		(27 "Margin" user)
		(31 "F.CrtYd" user "Package Geometry/Place Bound Top")
		(29 "B.CrtYd" user "Package Geometry/Place Bound Bottom")
		(35 "F.Fab" user "Ref Des/Assembly Top")
		(33 "B.Fab" user "Ref Des/Assembly Bottom")
	)
	(footprint ""
		(layer "F.Cu")
		(at 28.321 -25.781)
		(property "Reference" "PTC1"
			(at 0 0 0)
			(layer "F.SilkS")
			(hide yes)
			(effects
				(font
					(size 1.27 1.27)
				)
			)
		)
		(property "Value" "SE470UF2VDM-GP"
			(at -3.220466 1.242822 0)
			(unlocked yes)
			(layer "F.Fab")
			(hide yes)
			(effects
				(font
					(size 1.016 1.016)
					(thickness 0.1524)
				)
			)
		)
		(property "Device Type" "CT7343H83"
			(at -3.220466 -0.281178 0)
			(unlocked yes)
			(layer "F.Fab")
			(hide yes)
			(effects
				(font
					(size 1.016 1.016)
					(thickness 0.1524)
				)
			)
		)
		(duplicate_pad_numbers_are_jumpers no)
		(fp_line
			(start -2.206752 -4.2926)
			(end 2.155698 -4.2926)
			(stroke
				(width 0.508)
				(type default)
			)
			(layer "F.SilkS")
		)
		(fp_rect
			(start -2.1463 3.6449)
			(end 2.1463 -3.6449)
			(stroke
				(width 0)
				(type default)
			)
			(fill no)
			(layer "F.CrtYd")
		)
		(fp_poly
			(pts
				(xy -3.81 3.9116) (xy -3.81 -3.9116) (xy -2.54 -3.9116) (xy -2.4003 -3.9116) (xy -2.4003 -4.0386)
				(xy 2.4003 -4.0386) (xy 2.4003 -3.9116) (xy 2.54 -3.9116) (xy 2.5654 -3.9116) (xy 3.81 -3.9116)
				(xy 3.81 -1.6256) (xy 2.1463 -1.6256) (xy 2.1463 -3.6449) (xy -2.1463 -3.6449) (xy -2.1463 3.6449)
				(xy 2.1463 3.6449) (xy 2.1463 -1.6129) (xy 3.81 -1.6129) (xy 3.81 3.9116) (xy 2.4003 3.9116) (xy 2.4003 3.9243)
				(xy 2.4003 4.0386) (xy -2.4003 4.0386) (xy -2.4003 3.9116)
			)
			(stroke
				(width 0)
				(type default)
			)
			(fill no)
			(layer "F.CrtYd")
		)
		(fp_rect
			(start -3.81 3.9116)
			(end -2.4003 -3.9116)
			(stroke
				(width 0)
				(type default)
			)
			(fill no)
			(layer "F.Fab")
		)
		(fp_rect
			(start -2.4003 4.0386)
			(end 2.4003 -4.0386)
			(stroke
				(width 0)
				(type default)
			)
			(fill no)
			(layer "F.Fab")
		)
		(fp_rect
			(start 2.4003 3.9116)
			(end 3.81 -3.9116)
			(stroke
				(width 0)
				(type default)
			)
			(fill no)
			(layer "F.Fab")
		)
		(pad "1" smd rect
			(at 0 -2.9591)
			(size 2.413 1.905)
			(layers "F.Cu" "F.Mask" "F.Paste")
			(net "P1V0")
		)
		(pad "2" smd rect
			(at 0 2.9591)
			(size 2.413 1.905)
			(layers "F.Cu" "F.Mask" "F.Paste")
			(net "GND")
		)
	)
	(footprint ""
		(layer "F.Cu")
		(at 49.7078 -54.6481 -90)
		(property "Reference" "L1"
			(at 0 0 270)
			(layer "F.SilkS")
			(hide yes)
			(effects
				(font
					(size 1.27 1.27)
				)
			)
		)
		(property "Value" "BLM18PG330SN1D-GP"
			(at -0.0254 -2.0193 270)
			(unlocked yes)
			(layer "F.Fab")
			(hide yes)
			(effects
				(font
					(size 1.016 1.016)
					(thickness 0.1524)
				)
			)
		)
		(property "Device Type" "L1608-UH38"
			(at -0.0254 -3.5433 270)
			(unlocked yes)
			(layer "F.Fab")
			(hide yes)
			(effects
				(font
					(size 1.016 1.016)
					(thickness 0.1524)
				)
			)
		)
		(duplicate_pad_numbers_are_jumpers no)
		(fp_line
			(start -0.4064 0)
			(end 0.4064 0)
			(stroke
				(width 0.2032)
				(type default)
			)
			(layer "F.SilkS")
		)
		(fp_rect
			(start -0.635 1.1811)
			(end 0.635 -1.1811)
			(stroke
				(width 0)
				(type default)
			)
			(fill no)
			(layer "F.CrtYd")
		)
		(fp_rect
			(start -0.635 1.1811)
			(end 0.635 -1.1811)
			(stroke
				(width 0)
				(type default)
			)
			(fill no)
			(layer "F.Fab")
		)
		(pad "1" smd custom
			(at 0 -0.6604 270)
			(size 0.19685 0.19685)
			(layers "F.Cu" "F.Mask" "F.Paste")
			(net "P3V3_STBY")
			(options
				(clearance outline)
				(anchor circle)
			)
			(primitives
				(gr_poly
					(pts
						(arc
							(start 0.508 -0.2921)
							(mid 0.478242 -0.363942)
							(end 0.4064 -0.3937)
						)
						(arc
							(start -0.4064 -0.3937)
							(mid -0.478242 -0.363942)
							(end -0.508 -0.2921)
						)
						(arc
							(start -0.508 0.2921)
							(mid -0.478242 0.363942)
							(end -0.4064 0.3937)
						)
						(arc
							(start 0.4064 0.3937)
							(mid 0.478242 0.363942)
							(end 0.508 0.2921)
						)
					)
					(width 0)
					(fill yes)
				)
			)
		)
		(pad "2" smd custom
			(at 0 0.6604 270)
			(size 0.19685 0.19685)
			(layers "F.Cu" "F.Mask" "F.Paste")
			(net "P3V3_CLK_R_VDD25")
			(options
				(clearance outline)
				(anchor circle)
			)
			(primitives
				(gr_poly
					(pts
						(arc
							(start 0.508 -0.2921)
							(mid 0.478242 -0.363942)
							(end 0.4064 -0.3937)
						)
						(arc
							(start -0.4064 -0.3937)
							(mid -0.478242 -0.363942)
							(end -0.508 -0.2921)
						)
						(arc
							(start -0.508 0.2921)
							(mid -0.478242 0.363942)
							(end -0.4064 0.3937)
						)
						(arc
							(start 0.4064 0.3937)
							(mid 0.478242 0.363942)
							(end 0.508 0.2921)
						)
					)
					(width 0)
					(fill yes)
				)
			)
		)
	)
	(footprint ""
		(layer "F.Cu")
		(at 31.877 -35.0012 -90)
		(property "Reference" "R269"
			(at 0 0 270)
			(layer "F.SilkS")
			(hide yes)
			(effects
				(font
					(size 1.27 1.27)
				)
			)
		)
		(property "Value" "51R2F-2-GP"
			(at 0.064008 -3.993896 270)
			(unlocked yes)
			(layer "F.Fab")
			(hide yes)
			(effects
				(font
					(size 1.016 1.016)
					(thickness 0.1524)
				)
			)
		)
		(property "Device Type" "R402H16"
			(at 0.064008 -5.517896 270)
			(unlocked yes)
			(layer "F.Fab")
			(hide yes)
			(effects
				(font
					(size 1.016 1.016)
					(thickness 0.1524)
				)
			)
		)
		(duplicate_pad_numbers_are_jumpers no)
		(fp_rect
			(start -0.381 0.8382)
			(end 0.381 -0.8382)
			(stroke
				(width 0)
				(type default)
			)
			(fill no)
			(layer "F.CrtYd")
		)
		(fp_rect
			(start -0.381 0.8382)
			(end 0.381 -0.8382)
			(stroke
				(width 0)
				(type default)
			)
			(fill no)
			(layer "F.Fab")
		)
		(pad "1" smd custom
			(at 0 -0.4318 270)
			(size 0.127 0.127)
			(layers "F.Cu" "F.Mask" "F.Paste")
			(net "XDP_SOC_CPU_TRST#")
			(options
				(clearance outline)
				(anchor circle)
			)
			(primitives
				(gr_poly
					(pts
						(arc
							(start -0.2032 -0.2794)
							(mid -0.239121 -0.264521)
							(end -0.254 -0.2286)
						)
						(arc
							(start -0.254 0.2286)
							(mid -0.239121 0.264521)
							(end -0.2032 0.2794)
						)
						(arc
							(start 0.2032 0.2794)
							(mid 0.239121 0.264521)
							(end 0.254 0.2286)
						)
						(arc
							(start 0.254 -0.2286)
							(mid 0.239121 -0.264521)
							(end 0.2032 -0.2794)
						)
					)
					(width 0)
					(fill yes)
				)
			)
		)
		(pad "2" smd custom
			(at 0 0.4318 270)
			(size 0.127 0.127)
			(layers "F.Cu" "F.Mask" "F.Paste")
			(net "GND")
			(options
				(clearance outline)
				(anchor circle)
			)
			(primitives
				(gr_poly
					(pts
						(arc
							(start -0.2032 -0.2794)
							(mid -0.239121 -0.264521)
							(end -0.254 -0.2286)
						)
						(arc
							(start -0.254 0.2286)
							(mid -0.239121 0.264521)
							(end -0.2032 0.2794)
						)
						(arc
							(start 0.2032 0.2794)
							(mid 0.239121 0.264521)
							(end 0.254 0.2286)
						)
						(arc
							(start 0.254 -0.2286)
							(mid 0.239121 -0.264521)
							(end 0.2032 -0.2794)
						)
					)
					(width 0)
					(fill yes)
				)
			)
		)
	)
	(footprint ""
		(layer "F.Cu")
		(at 47.625 -16.0782 180)
		(property "Reference" "R346"
			(at 0 0 180)
			(layer "F.SilkS")
			(hide yes)
			(effects
				(font
					(size 1.27 1.27)
				)
			)
		)
		(property "Value" "4K7R2F-GP"
			(at 0.064008 -3.993896 180)
			(unlocked yes)
			(layer "F.Fab")
			(hide yes)
			(effects
				(font
					(size 1.016 1.016)
					(thickness 0.1524)
				)
			)
		)
		(property "Device Type" "R402H16"
			(at 0.064008 -5.517896 180)
			(unlocked yes)
			(layer "F.Fab")
			(hide yes)
			(effects
				(font
					(size 1.016 1.016)
					(thickness 0.1524)
				)
			)
		)
		(duplicate_pad_numbers_are_jumpers no)
		(fp_rect
			(start -0.381 0.8382)
			(end 0.381 -0.8382)
			(stroke
				(width 0)
				(type default)
			)
			(fill no)
			(layer "F.CrtYd")
		)
		(fp_rect
			(start -0.381 0.8382)
			(end 0.381 -0.8382)
			(stroke
				(width 0)
				(type default)
			)
			(fill no)
			(layer "F.Fab")
		)
		(pad "1" smd custom
			(at 0 -0.4318 180)
			(size 0.127 0.127)
			(layers "F.Cu" "F.Mask" "F.Paste")
			(net "P3V3")
			(options
				(clearance outline)
				(anchor circle)
			)
			(primitives
				(gr_poly
					(pts
						(arc
							(start -0.2032 -0.2794)
							(mid -0.239121 -0.264521)
							(end -0.254 -0.2286)
						)
						(arc
							(start -0.254 0.2286)
							(mid -0.239121 0.264521)
							(end -0.2032 0.2794)
						)
						(arc
							(start 0.2032 0.2794)
							(mid 0.239121 0.264521)
							(end 0.254 0.2286)
						)
						(arc
							(start 0.254 -0.2286)
							(mid 0.239121 -0.264521)
							(end 0.2032 -0.2794)
						)
					)
					(width 0)
					(fill yes)
				)
			)
		)
		(pad "2" smd custom
			(at 0 0.4318 180)
			(size 0.127 0.127)
			(layers "F.Cu" "F.Mask" "F.Paste")
			(net "CLKBUFF_OE1#")
			(options
				(clearance outline)
				(anchor circle)
			)
			(primitives
				(gr_poly
					(pts
						(arc
							(start -0.2032 -0.2794)
							(mid -0.239121 -0.264521)
							(end -0.254 -0.2286)
						)
						(arc
							(start -0.254 0.2286)
							(mid -0.239121 0.264521)
							(end -0.2032 0.2794)
						)
						(arc
							(start 0.2032 0.2794)
							(mid 0.239121 0.264521)
							(end 0.254 0.2286)
						)
						(arc
							(start 0.254 -0.2286)
							(mid 0.239121 -0.264521)
							(end 0.2032 -0.2794)
						)
					)
					(width 0)
					(fill yes)
				)
			)
		)
	)
	(footprint ""
		(layer "F.Cu")
		(at 185.76036 -18.69821 180)
		(property "Reference" "PU12"
			(at 0 0 180)
			(layer "F.SilkS")
			(hide yes)
			(effects
				(font
					(size 1.27 1.27)
				)
			)
		)
		(property "Value" "TPS51200-GP-U1"
			(at 2.9083 1.397 180)
			(unlocked yes)
			(layer "F.Fab")
			(hide yes)
			(effects
				(font
					(size 1.016 1.016)
					(thickness 0.1524)
				)
			)
		)
		(property "Device Type" "QFN10-G4H40"
			(at 2.9083 -0.127 180)
			(unlocked yes)
			(layer "F.Fab")
			(hide yes)
			(effects
				(font
					(size 1.016 1.016)
					(thickness 0.1524)
				)
			)
		)
		(duplicate_pad_numbers_are_jumpers no)
		(fp_poly
			(pts
				(xy 1.0287 -2.0066) (xy 1.27 -2.2479) (xy 0.7874 -2.2479)
			)
			(stroke
				(width 0)
				(type default)
			)
			(fill yes)
			(layer "F.SilkS")
		)
		(fp_rect
			(start -1.7526 2.0066)
			(end 1.7526 -2.0066)
			(stroke
				(width 0)
				(type default)
			)
			(fill no)
			(layer "F.CrtYd")
		)
		(fp_rect
			(start -1.7526 2.0066)
			(end 1.7526 -2.0066)
			(stroke
				(width 0)
				(type default)
			)
			(fill no)
			(layer "F.Fab")
		)
		(pad "1" smd rect
			(at 0.999998 -1.4605 180)
			(size 0.3048 0.8382)
			(layers "F.Cu" "F.Mask" "F.Paste")
			(net "PV_VTT_DDR_B_REFIN")
		)
		(pad "2" smd rect
			(at 0.500126 -1.4605 180)
			(size 0.3048 0.8382)
			(layers "F.Cu" "F.Mask" "F.Paste")
			(net "PV_VDDR")
		)
		(pad "3" smd rect
			(at 0 -1.4605 180)
			(size 0.3048 0.8382)
			(layers "F.Cu" "F.Mask" "F.Paste")
			(net "PV_VTT_DDR_B")
		)
		(pad "4" smd rect
			(at -0.500126 -1.4605 180)
			(size 0.3048 0.8382)
			(layers "F.Cu" "F.Mask" "F.Paste")
			(net "GND")
		)
		(pad "5" smd rect
			(at -0.999998 -1.4605 180)
			(size 0.3048 0.8382)
			(layers "F.Cu" "F.Mask" "F.Paste")
			(net "PV_VTT_DDR_B_SNS")
		)
		(pad "6" smd rect
			(at -0.999998 1.4605 180)
			(size 0.3048 0.8382)
			(layers "F.Cu" "F.Mask" "F.Paste")
			(net "PV_VTT_DDR_B_REFO")
		)
		(pad "7" smd rect
			(at -0.500126 1.4605 180)
			(size 0.3048 0.8382)
			(layers "F.Cu" "F.Mask" "F.Paste")
			(net "PV_VTT_DDR_B_EN")
		)
		(pad "8" smd rect
			(at 0 1.4605 180)
			(size 0.3048 0.8382)
			(layers "F.Cu" "F.Mask" "F.Paste")
			(net "GND")
		)
		(pad "9" smd rect
			(at 0.500126 1.4605 180)
			(size 0.3048 0.8382)
			(layers "F.Cu" "F.Mask" "F.Paste")
			(net "PV_VTT_DDR_B_R_PG")
		)
		(pad "10" smd rect
			(at 0.999998 1.4605 180)
			(size 0.3048 0.8382)
			(layers "F.Cu" "F.Mask" "F.Paste")
			(net "PV_VTT_DDR_B_VIN")
		)
		(pad "11" smd rect
			(at 0 0 180)
			(size 2.9972 1.6764)
			(layers "F.Cu" "F.Mask" "F.Paste")
			(net "GND")
		)
	)
	(footprint ""
		(layer "F.Cu")
		(at 100.6094 -67.5894 -90)
		(property "Reference" "PR9"
			(at 0 0 270)
			(layer "F.SilkS")
			(hide yes)
			(effects
				(font
					(size 1.27 1.27)
				)
			)
		)
		(property "Value" "10KR2F-2-GP"
			(at 0.064008 -3.993896 270)
			(unlocked yes)
			(layer "F.Fab")
			(hide yes)
			(effects
				(font
					(size 1.016 1.016)
					(thickness 0.1524)
				)
			)
		)
		(property "Device Type" "R402H16"
			(at 0.064008 -5.517896 270)
			(unlocked yes)
			(layer "F.Fab")
			(hide yes)
			(effects
				(font
					(size 1.016 1.016)
					(thickness 0.1524)
				)
			)
		)
		(duplicate_pad_numbers_are_jumpers no)
		(fp_rect
			(start -0.381 0.8382)
			(end 0.381 -0.8382)
			(stroke
				(width 0)
				(type default)
			)
			(fill no)
			(layer "F.CrtYd")
		)
		(fp_rect
			(start -0.381 0.8382)
			(end 0.381 -0.8382)
			(stroke
				(width 0)
				(type default)
			)
			(fill no)
			(layer "F.Fab")
		)
		(pad "1" smd custom
			(at 0 -0.4318 270)
			(size 0.127 0.127)
			(layers "F.Cu" "F.Mask" "F.Paste")
			(net "P3V3_STBY")
			(options
				(clearance outline)
				(anchor circle)
			)
			(primitives
				(gr_poly
					(pts
						(arc
							(start -0.2032 -0.2794)
							(mid -0.239121 -0.264521)
							(end -0.254 -0.2286)
						)
						(arc
							(start -0.254 0.2286)
							(mid -0.239121 0.264521)
							(end -0.2032 0.2794)
						)
						(arc
							(start 0.2032 0.2794)
							(mid 0.239121 0.264521)
							(end 0.254 0.2286)
						)
						(arc
							(start 0.254 -0.2286)
							(mid 0.239121 -0.264521)
							(end 0.2032 -0.2794)
						)
					)
					(width 0)
					(fill yes)
				)
			)
		)
		(pad "2" smd custom
			(at 0 0.4318 270)
			(size 0.127 0.127)
			(layers "F.Cu" "F.Mask" "F.Paste")
			(net "VR_P1V1_EN")
			(options
				(clearance outline)
				(anchor circle)
			)
			(primitives
				(gr_poly
					(pts
						(arc
							(start -0.2032 -0.2794)
							(mid -0.239121 -0.264521)
							(end -0.254 -0.2286)
						)
						(arc
							(start -0.254 0.2286)
							(mid -0.239121 0.264521)
							(end -0.2032 0.2794)
						)
						(arc
							(start 0.2032 0.2794)
							(mid 0.239121 0.264521)
							(end 0.254 0.2286)
						)
						(arc
							(start 0.254 -0.2286)
							(mid 0.239121 -0.264521)
							(end 0.2032 -0.2794)
						)
					)
					(width 0)
					(fill yes)
				)
			)
		)
	)
	(footprint ""
		(layer "F.Cu")
		(at 44.323 -54.229 -90)
		(property "Reference" "PC34"
			(at 0 0 270)
			(layer "F.SilkS")
			(hide yes)
			(effects
				(font
					(size 1.27 1.27)
				)
			)
		)
		(property "Value" "SC3300P50V3KX-1GP"
			(at -0.0254 -2.0193 270)
			(unlocked yes)
			(layer "F.Fab")
			(hide yes)
			(effects
				(font
					(size 1.016 1.016)
					(thickness 0.1524)
				)
			)
		)
		(property "Device Type" "C603H36"
			(at -0.0254 -3.5433 270)
			(unlocked yes)
			(layer "F.Fab")
			(hide yes)
			(effects
				(font
					(size 1.016 1.016)
					(thickness 0.1524)
				)
			)
		)
		(duplicate_pad_numbers_are_jumpers no)
		(fp_line
			(start -0.4064 0)
			(end 0.4064 0)
			(stroke
				(width 0.2286)
				(type default)
			)
			(layer "F.SilkS")
		)
		(fp_rect
			(start -0.635 1.1811)
			(end 0.635 -1.1811)
			(stroke
				(width 0)
				(type default)
			)
			(fill no)
			(layer "F.CrtYd")
		)
		(fp_rect
			(start -0.635 1.1811)
			(end 0.635 -1.1811)
			(stroke
				(width 0)
				(type default)
			)
			(fill no)
			(layer "F.Fab")
		)
		(pad "1" smd custom
			(at 0 -0.6604 270)
			(size 0.19685 0.19685)
			(layers "F.Cu" "F.Mask" "F.Paste")
			(net "VR_PVCCP_PWM_OUT")
			(options
				(clearance outline)
				(anchor circle)
			)
			(primitives
				(gr_poly
					(pts
						(arc
							(start 0.508 -0.2921)
							(mid 0.478242 -0.363942)
							(end 0.4064 -0.3937)
						)
						(arc
							(start -0.4064 -0.3937)
							(mid -0.478242 -0.363942)
							(end -0.508 -0.2921)
						)
						(arc
							(start -0.508 0.2921)
							(mid -0.478242 0.363942)
							(end -0.4064 0.3937)
						)
						(arc
							(start 0.4064 0.3937)
							(mid 0.478242 0.363942)
							(end 0.508 0.2921)
						)
					)
					(width 0)
					(fill yes)
				)
			)
		)
		(pad "2" smd custom
			(at 0 0.6604 270)
			(size 0.19685 0.19685)
			(layers "F.Cu" "F.Mask" "F.Paste")
			(net "VR_PVCCP_VSW_R")
			(options
				(clearance outline)
				(anchor circle)
			)
			(primitives
				(gr_poly
					(pts
						(arc
							(start 0.508 -0.2921)
							(mid 0.478242 -0.363942)
							(end 0.4064 -0.3937)
						)
						(arc
							(start -0.4064 -0.3937)
							(mid -0.478242 -0.363942)
							(end -0.508 -0.2921)
						)
						(arc
							(start -0.508 0.2921)
							(mid -0.478242 0.363942)
							(end -0.4064 0.3937)
						)
						(arc
							(start 0.4064 0.3937)
							(mid 0.478242 0.363942)
							(end 0.508 0.2921)
						)
					)
					(width 0)
					(fill yes)
				)
			)
		)
	)
)
